# T6G (Grand Teton) — schematic netlist excerpt (pin names and nets, part order shuffled) for the footprints in the layout excerpt that follows; sources: Cadence DE-HDL packaged netlist, KiCad conversion of 04192023_DAF0TMB3IC0_F0TG_MB_C_brd_V02_OCP.brd

R21  Q_RES  1K 1% EMPTY  pkg 0402LF  page 77 : A = P3V3_AUX ; B = SPI_CPU0_LVC3_SCM_D0
PC205_11P0_1  Q_CAP  2.2UF 10V 10% X6S  pkg C0402  page 208 : A = PVDD11_S3_P0_PVCC ; B = GND

(kicad_pcb
	(version 20260206)
	(generator "pcbnew")
	(generator_version "10.0")
	(general
		(thickness 1.6)
		(legacy_teardrops no)
	)
	(paper "A4")
	(title_block
		(title "04192023_DAF0TMB3IC0_F0TG_MB_C_brd_V02_OCP.brd")
		(comment 1 "Grand Teton / footprints 289-290 of 8354")
	)
	(layers
		(0 "F.Cu" signal "TOP")
		(4 "In1.Cu" signal "GND")
		(6 "In2.Cu" signal "IN1")
		(8 "In3.Cu" signal "GND1")
		(10 "In4.Cu" signal "IN2")
		(12 "In5.Cu" signal "GND2")
		(14 "In6.Cu" signal "IN3")
		(16 "In7.Cu" signal "GND3")
		(18 "In8.Cu" signal "VCC")
		(20 "In9.Cu" signal "VCC1")
		(22 "In10.Cu" signal "GND4")
		(24 "In11.Cu" signal "IN4")
		(26 "In12.Cu" signal "GND5")
		(28 "In13.Cu" signal "IN5")
		(30 "In14.Cu" signal "GND6")
		(32 "In15.Cu" signal "IN6")
		(34 "In16.Cu" signal "GND7")
		(2 "B.Cu" signal "BOTTOM")
		(9 "F.Adhes" user "F.Adhesive")
		(11 "B.Adhes" user "B.Adhesive")
		(13 "F.Paste" user "Package Geometry/Pastemask Top")
		(15 "B.Paste" user "Package Geometry/Pastemask Bottom")
		(5 "F.SilkS" user "Ref Des/Silkscreen Top")
		(7 "B.SilkS" user "Ref Des/Silkscreen Bottom")
		(1 "F.Mask" user "Board Geometry/Soldermask Top")
		(3 "B.Mask" user "Board Geometry/Soldermask Bottom")
		(17 "Dwgs.User" user "User.Drawings")
		(19 "Cmts.User" user "User.Comments")
		(21 "Eco1.User" user "User.Eco1")
		(23 "Eco2.User" user "User.Eco2")
		(25 "Edge.Cuts" user "Board Geometry/Outline")
		(27 "Margin" user)
		(31 "F.CrtYd" user "Package Geometry/Place Bound Top")
		(29 "B.CrtYd" user "Package Geometry/Place Bound Bottom")
		(35 "F.Fab" user "Ref Des/Assembly Top")
		(33 "B.Fab" user "Ref Des/Assembly Bottom")
	)
	(footprint ""
		(layer "F.Cu")
		(at 419.96106 -351.11309 -90)
		(property "Reference" "PC205_11P0_1"
			(at 0 0 270)
			(layer "F.SilkS")
			(hide yes)
			(effects
				(font
					(size 1.27 1.27)
				)
			)
		)
		(property "Value" ""
			(at 0 0 270)
			(layer "F.Fab")
			(effects
				(font
					(size 1.27 1.27)
				)
			)
		)
		(duplicate_pad_numbers_are_jumpers no)
		(fp_line
			(start -0.7874 0.4064)
			(end -0.7874 -0.4064)
			(stroke
				(width 0.1524)
				(type default)
			)
			(layer "F.SilkS")
		)
		(fp_line
			(start 0.7874 0.4064)
			(end -0.7874 0.4064)
			(stroke
				(width 0.1524)
				(type default)
			)
			(layer "F.SilkS")
		)
		(fp_line
			(start -0.7874 -0.4064)
			(end 0.7874 -0.4064)
			(stroke
				(width 0.1524)
				(type default)
			)
			(layer "F.SilkS")
		)
		(fp_line
			(start 0.7874 -0.4064)
			(end 0.7874 0.4064)
			(stroke
				(width 0.1524)
				(type default)
			)
			(layer "F.SilkS")
		)
		(fp_line
			(start -0.67945 0.3048)
			(end -0.67945 -0.305054)
			(stroke
				(width 0.1)
				(type default)
			)
			(layer "F.Fab")
		)
		(fp_line
			(start -0.12065 0.3048)
			(end -0.67945 0.3048)
			(stroke
				(width 0.1)
				(type default)
			)
			(layer "F.Fab")
		)
		(fp_line
			(start 0.120396 0.3048)
			(end 0.120396 0.2794)
			(stroke
				(width 0.1)
				(type default)
			)
			(layer "F.Fab")
		)
		(fp_line
			(start 0.67945 0.3048)
			(end 0.120396 0.3048)
			(stroke
				(width 0.1)
				(type default)
			)
			(layer "F.Fab")
		)
		(fp_line
			(start -0.12065 0.2794)
			(end -0.12065 0.3048)
			(stroke
				(width 0.1)
				(type default)
			)
			(layer "F.Fab")
		)
		(fp_line
			(start 0.120396 0.2794)
			(end -0.12065 0.2794)
			(stroke
				(width 0.1)
				(type default)
			)
			(layer "F.Fab")
		)
		(fp_line
			(start -0.12065 -0.2794)
			(end 0.12065 -0.2794)
			(stroke
				(width 0.1)
				(type default)
			)
			(layer "F.Fab")
		)
		(fp_line
			(start 0.12065 -0.2794)
			(end 0.12065 -0.3048)
			(stroke
				(width 0.1)
				(type default)
			)
			(layer "F.Fab")
		)
		(fp_line
			(start 0.12065 -0.3048)
			(end 0.67945 -0.3048)
			(stroke
				(width 0.1)
				(type default)
			)
			(layer "F.Fab")
		)
		(fp_line
			(start 0.67945 -0.3048)
			(end 0.67945 0.3048)
			(stroke
				(width 0.1)
				(type default)
			)
			(layer "F.Fab")
		)
		(fp_line
			(start -0.67945 -0.305054)
			(end -0.12065 -0.305054)
			(stroke
				(width 0.1)
				(type default)
			)
			(layer "F.Fab")
		)
		(fp_line
			(start -0.12065 -0.305054)
			(end -0.12065 -0.2794)
			(stroke
				(width 0.1)
				(type default)
			)
			(layer "F.Fab")
		)
		(pad "1" smd circle
			(at -0.40005 0 270)
			(size 0 0)
			(layers "F.Cu" "F.Mask" "F.Paste")
			(net "PVDD11_S3_P0_PVCC")
		)
		(pad "2" smd circle
			(at 0.40005 0 270)
			(size 0 0)
			(layers "F.Cu" "F.Mask" "F.Paste")
			(net "GND")
		)
	)
	(footprint ""
		(layer "F.Cu")
		(at 257.683 -142.367)
		(property "Reference" "R21"
			(at 0 0 0)
			(layer "F.SilkS")
			(hide yes)
			(effects
				(font
					(size 1.27 1.27)
				)
			)
		)
		(property "Value" ""
			(at 0 0 0)
			(layer "F.Fab")
			(effects
				(font
					(size 1.27 1.27)
				)
			)
		)
		(duplicate_pad_numbers_are_jumpers no)
		(fp_line
			(start -0.7874 -0.4064)
			(end 0.7874 -0.4064)
			(stroke
				(width 0.1524)
				(type default)
			)
			(layer "F.SilkS")
		)
		(fp_line
			(start -0.7874 0.4064)
			(end -0.7874 -0.4064)
			(stroke
				(width 0.1524)
				(type default)
			)
			(layer "F.SilkS")
		)
		(fp_line
			(start 0.7874 -0.4064)
			(end 0.7874 0.4064)
			(stroke
				(width 0.1524)
				(type default)
			)
			(layer "F.SilkS")
		)
		(fp_line
			(start 0.7874 0.4064)
			(end -0.7874 0.4064)
			(stroke
				(width 0.1524)
				(type default)
			)
			(layer "F.SilkS")
		)
		(fp_line
			(start -0.67945 -0.305054)
			(end -0.12065 -0.305054)
			(stroke
				(width 0.1)
				(type default)
			)
			(layer "F.Fab")
		)
		(fp_line
			(start -0.67945 0.3048)
			(end -0.67945 -0.305054)
			(stroke
				(width 0.1)
				(type default)
			)
			(layer "F.Fab")
		)
		(fp_line
			(start -0.12065 -0.305054)
			(end -0.12065 -0.2794)
			(stroke
				(width 0.1)
				(type default)
			)
			(layer "F.Fab")
		)
		(fp_line
			(start -0.12065 -0.2794)
			(end 0.12065 -0.2794)
			(stroke
				(width 0.1)
				(type default)
			)
			(layer "F.Fab")
		)
		(fp_line
			(start -0.12065 0.2794)
			(end -0.12065 0.3048)
			(stroke
				(width 0.1)
				(type default)
			)
			(layer "F.Fab")
		)
		(fp_line
			(start -0.12065 0.3048)
			(end -0.67945 0.3048)
			(stroke
				(width 0.1)
				(type default)
			)
			(layer "F.Fab")
		)
		(fp_line
			(start 0.120396 0.2794)
			(end -0.12065 0.2794)
			(stroke
				(width 0.1)
				(type default)
			)
			(layer "F.Fab")
		)
		(fp_line
			(start 0.120396 0.3048)
			(end 0.120396 0.2794)
			(stroke
				(width 0.1)
				(type default)
			)
			(layer "F.Fab")
		)
		(fp_line
			(start 0.12065 -0.3048)
			(end 0.67945 -0.3048)
			(stroke
				(width 0.1)
				(type default)
			)
			(layer "F.Fab")
		)
		(fp_line
			(start 0.12065 -0.2794)
			(end 0.12065 -0.3048)
			(stroke
				(width 0.1)
				(type default)
			)
			(layer "F.Fab")
		)
		(fp_line
			(start 0.67945 -0.3048)
			(end 0.67945 0.3048)
			(stroke
				(width 0.1)
				(type default)
			)
			(layer "F.Fab")
		)
		(fp_line
			(start 0.67945 0.3048)
			(end 0.120396 0.3048)
			(stroke
				(width 0.1)
				(type default)
			)
			(layer "F.Fab")
		)
		(pad "1" smd circle
			(at -0.40005 0)
			(size 0 0)
			(layers "F.Cu" "F.Mask" "F.Paste")
			(net "P3V3_AUX")
		)
		(pad "2" smd circle
			(at 0.40005 0)
			(size 0 0)
			(layers "F.Cu" "F.Mask" "F.Paste")
			(net "SPI_CPU0_LVC3_SCM_D0")
		)
	)
)
